# T6G (Grand Teton) — schematic netlist excerpt (pin names and nets, part order shuffled) for the footprints in the layout excerpt that follows; sources: Cadence DE-HDL packaged netlist, KiCad conversion of 04192023_DAF0TMB3IC0_F0TG_MB_C_brd_V02_OCP.brd

Q64  MOSFET_N  BSS138K IC  pkg SMLF  page 174
  DRAIN  = FM_PLD_CPU1_PRSNT_HDT_N
  GATE  = CPU1_HDT_BYPASS_SEL
  SOURCE  = GND

R2565  Q_RES  0 5% CHIP  pkg 0402LF  page 250 : A = SMB_FRU_3V3AUX_SCL_R ; B = SMB_FRU_3V3AUX_SCL
PC4056  Q_CAP  3900PF 50V 10% X7R  pkg C0402  page 134 : A = P12V_OCP_GATE_1 ; B = GND

(kicad_pcb
	(version 20260206)
	(generator "pcbnew")
	(generator_version "10.0")
	(general
		(thickness 1.6)
		(legacy_teardrops no)
	)
	(paper "A4")
	(title_block
		(title "04192023_DAF0TMB3IC0_F0TG_MB_C_brd_V02_OCP.brd")
		(comment 1 "Grand Teton / footprints 2241-2243 of 8354")
	)
	(layers
		(0 "F.Cu" signal "TOP")
		(4 "In1.Cu" signal "GND")
		(6 "In2.Cu" signal "IN1")
		(8 "In3.Cu" signal "GND1")
		(10 "In4.Cu" signal "IN2")
		(12 "In5.Cu" signal "GND2")
		(14 "In6.Cu" signal "IN3")
		(16 "In7.Cu" signal "GND3")
		(18 "In8.Cu" signal "VCC")
		(20 "In9.Cu" signal "VCC1")
		(22 "In10.Cu" signal "GND4")
		(24 "In11.Cu" signal "IN4")
		(26 "In12.Cu" signal "GND5")
		(28 "In13.Cu" signal "IN5")
		(30 "In14.Cu" signal "GND6")
		(32 "In15.Cu" signal "IN6")
		(34 "In16.Cu" signal "GND7")
		(2 "B.Cu" signal "BOTTOM")
		(9 "F.Adhes" user "F.Adhesive")
		(11 "B.Adhes" user "B.Adhesive")
		(13 "F.Paste" user "Package Geometry/Pastemask Top")
		(15 "B.Paste" user "Package Geometry/Pastemask Bottom")
		(5 "F.SilkS" user "Ref Des/Silkscreen Top")
		(7 "B.SilkS" user "Ref Des/Silkscreen Bottom")
		(1 "F.Mask" user "Board Geometry/Soldermask Top")
		(3 "B.Mask" user "Board Geometry/Soldermask Bottom")
		(17 "Dwgs.User" user "User.Drawings")
		(19 "Cmts.User" user "User.Comments")
		(21 "Eco1.User" user "User.Eco1")
		(23 "Eco2.User" user "User.Eco2")
		(25 "Edge.Cuts" user "Board Geometry/Outline")
		(27 "Margin" user)
		(31 "F.CrtYd" user "Package Geometry/Place Bound Top")
		(29 "B.CrtYd" user "Package Geometry/Place Bound Bottom")
		(35 "F.Fab" user "Ref Des/Assembly Top")
		(33 "B.Fab" user "Ref Des/Assembly Bottom")
	)
	(footprint ""
		(layer "F.Cu")
		(at 453.054212 -23.603458)
		(property "Reference" "PC4056"
			(at 0 0 0)
			(layer "F.SilkS")
			(hide yes)
			(effects
				(font
					(size 1.27 1.27)
				)
			)
		)
		(property "Value" ""
			(at 0 0 0)
			(layer "F.Fab")
			(effects
				(font
					(size 1.27 1.27)
				)
			)
		)
		(duplicate_pad_numbers_are_jumpers no)
		(fp_line
			(start -0.7874 -0.4064)
			(end 0.7874 -0.4064)
			(stroke
				(width 0.1524)
				(type default)
			)
			(layer "F.SilkS")
		)
		(fp_line
			(start -0.7874 0.4064)
			(end -0.7874 -0.4064)
			(stroke
				(width 0.1524)
				(type default)
			)
			(layer "F.SilkS")
		)
		(fp_line
			(start 0.7874 -0.4064)
			(end 0.7874 0.4064)
			(stroke
				(width 0.1524)
				(type default)
			)
			(layer "F.SilkS")
		)
		(fp_line
			(start 0.7874 0.4064)
			(end -0.7874 0.4064)
			(stroke
				(width 0.1524)
				(type default)
			)
			(layer "F.SilkS")
		)
		(fp_line
			(start -0.67945 -0.305054)
			(end -0.12065 -0.305054)
			(stroke
				(width 0.1)
				(type default)
			)
			(layer "F.Fab")
		)
		(fp_line
			(start -0.67945 0.3048)
			(end -0.67945 -0.305054)
			(stroke
				(width 0.1)
				(type default)
			)
			(layer "F.Fab")
		)
		(fp_line
			(start -0.12065 -0.305054)
			(end -0.12065 -0.2794)
			(stroke
				(width 0.1)
				(type default)
			)
			(layer "F.Fab")
		)
		(fp_line
			(start -0.12065 -0.2794)
			(end 0.12065 -0.2794)
			(stroke
				(width 0.1)
				(type default)
			)
			(layer "F.Fab")
		)
		(fp_line
			(start -0.12065 0.2794)
			(end -0.12065 0.3048)
			(stroke
				(width 0.1)
				(type default)
			)
			(layer "F.Fab")
		)
		(fp_line
			(start -0.12065 0.3048)
			(end -0.67945 0.3048)
			(stroke
				(width 0.1)
				(type default)
			)
			(layer "F.Fab")
		)
		(fp_line
			(start 0.120396 0.2794)
			(end -0.12065 0.2794)
			(stroke
				(width 0.1)
				(type default)
			)
			(layer "F.Fab")
		)
		(fp_line
			(start 0.120396 0.3048)
			(end 0.120396 0.2794)
			(stroke
				(width 0.1)
				(type default)
			)
			(layer "F.Fab")
		)
		(fp_line
			(start 0.12065 -0.3048)
			(end 0.67945 -0.3048)
			(stroke
				(width 0.1)
				(type default)
			)
			(layer "F.Fab")
		)
		(fp_line
			(start 0.12065 -0.2794)
			(end 0.12065 -0.3048)
			(stroke
				(width 0.1)
				(type default)
			)
			(layer "F.Fab")
		)
		(fp_line
			(start 0.67945 -0.3048)
			(end 0.67945 0.3048)
			(stroke
				(width 0.1)
				(type default)
			)
			(layer "F.Fab")
		)
		(fp_line
			(start 0.67945 0.3048)
			(end 0.120396 0.3048)
			(stroke
				(width 0.1)
				(type default)
			)
			(layer "F.Fab")
		)
		(pad "1" smd circle
			(at -0.40005 0)
			(size 0 0)
			(layers "F.Cu" "F.Mask" "F.Paste")
			(net "P12V_OCP_GATE_1")
		)
		(pad "2" smd circle
			(at 0.40005 0)
			(size 0 0)
			(layers "F.Cu" "F.Mask" "F.Paste")
			(net "GND")
		)
	)
	(footprint ""
		(layer "F.Cu")
		(at 294.421052 -117.269514)
		(property "Reference" "R2565"
			(at 0 0 0)
			(layer "F.SilkS")
			(hide yes)
			(effects
				(font
					(size 1.27 1.27)
				)
			)
		)
		(property "Value" ""
			(at 0 0 0)
			(layer "F.Fab")
			(effects
				(font
					(size 1.27 1.27)
				)
			)
		)
		(duplicate_pad_numbers_are_jumpers no)
		(fp_line
			(start -0.7874 -0.4064)
			(end 0.7874 -0.4064)
			(stroke
				(width 0.1524)
				(type default)
			)
			(layer "F.SilkS")
		)
		(fp_line
			(start -0.7874 0.4064)
			(end -0.7874 -0.4064)
			(stroke
				(width 0.1524)
				(type default)
			)
			(layer "F.SilkS")
		)
		(fp_line
			(start 0.7874 -0.4064)
			(end 0.7874 0.4064)
			(stroke
				(width 0.1524)
				(type default)
			)
			(layer "F.SilkS")
		)
		(fp_line
			(start 0.7874 0.4064)
			(end -0.7874 0.4064)
			(stroke
				(width 0.1524)
				(type default)
			)
			(layer "F.SilkS")
		)
		(fp_line
			(start -0.67945 -0.305054)
			(end -0.12065 -0.305054)
			(stroke
				(width 0.1)
				(type default)
			)
			(layer "F.Fab")
		)
		(fp_line
			(start -0.67945 0.3048)
			(end -0.67945 -0.305054)
			(stroke
				(width 0.1)
				(type default)
			)
			(layer "F.Fab")
		)
		(fp_line
			(start -0.12065 -0.305054)
			(end -0.12065 -0.2794)
			(stroke
				(width 0.1)
				(type default)
			)
			(layer "F.Fab")
		)
		(fp_line
			(start -0.12065 -0.2794)
			(end 0.12065 -0.2794)
			(stroke
				(width 0.1)
				(type default)
			)
			(layer "F.Fab")
		)
		(fp_line
			(start -0.12065 0.2794)
			(end -0.12065 0.3048)
			(stroke
				(width 0.1)
				(type default)
			)
			(layer "F.Fab")
		)
		(fp_line
			(start -0.12065 0.3048)
			(end -0.67945 0.3048)
			(stroke
				(width 0.1)
				(type default)
			)
			(layer "F.Fab")
		)
		(fp_line
			(start 0.120396 0.2794)
			(end -0.12065 0.2794)
			(stroke
				(width 0.1)
				(type default)
			)
			(layer "F.Fab")
		)
		(fp_line
			(start 0.120396 0.3048)
			(end 0.120396 0.2794)
			(stroke
				(width 0.1)
				(type default)
			)
			(layer "F.Fab")
		)
		(fp_line
			(start 0.12065 -0.3048)
			(end 0.67945 -0.3048)
			(stroke
				(width 0.1)
				(type default)
			)
			(layer "F.Fab")
		)
		(fp_line
			(start 0.12065 -0.2794)
			(end 0.12065 -0.3048)
			(stroke
				(width 0.1)
				(type default)
			)
			(layer "F.Fab")
		)
		(fp_line
			(start 0.67945 -0.3048)
			(end 0.67945 0.3048)
			(stroke
				(width 0.1)
				(type default)
			)
			(layer "F.Fab")
		)
		(fp_line
			(start 0.67945 0.3048)
			(end 0.120396 0.3048)
			(stroke
				(width 0.1)
				(type default)
			)
			(layer "F.Fab")
		)
		(pad "1" smd circle
			(at -0.40005 0)
			(size 0 0)
			(layers "F.Cu" "F.Mask" "F.Paste")
			(net "SMB_FRU_3V3AUX_SCL_R")
		)
		(pad "2" smd circle
			(at 0.40005 0)
			(size 0 0)
			(layers "F.Cu" "F.Mask" "F.Paste")
			(net "SMB_FRU_3V3AUX_SCL")
		)
	)
	(footprint ""
		(layer "F.Cu")
		(at 218.31681 -135.78459)
		(property "Reference" "Q64"
			(at -1.4224 -2.327148 0)
			(unlocked yes)
			(layer "F.SilkS")
			(effects
				(font
					(size 0.7874 0.5842)
					(thickness 0.1524)
				)
			)
		)
		(property "Value" ""
			(at 0 0 0)
			(layer "F.Fab")
			(effects
				(font
					(size 1.27 1.27)
				)
			)
		)
		(duplicate_pad_numbers_are_jumpers no)
		(fp_line
			(start -1.949958 -1.610106)
			(end 1.949958 -1.610106)
			(stroke
				(width 0.1524)
				(type default)
			)
			(layer "F.SilkS")
		)
		(fp_line
			(start -1.949958 1.610106)
			(end -1.949958 -1.610106)
			(stroke
				(width 0.1524)
				(type default)
			)
			(layer "F.SilkS")
		)
		(fp_line
			(start 1.949958 -1.560068)
			(end 1.949958 1.610106)
			(stroke
				(width 0.1524)
				(type default)
			)
			(layer "F.SilkS")
		)
		(fp_line
			(start 1.949958 1.610106)
			(end -1.949958 1.610106)
			(stroke
				(width 0.1524)
				(type default)
			)
			(layer "F.SilkS")
		)
		(fp_line
			(start -0.750062 -1.560068)
			(end 0.750062 -1.560068)
			(stroke
				(width 0.1)
				(type default)
			)
			(layer "F.Fab")
		)
		(fp_line
			(start -0.750062 1.560068)
			(end -0.750062 -1.560068)
			(stroke
				(width 0.1)
				(type default)
			)
			(layer "F.Fab")
		)
		(fp_line
			(start 0.750062 -1.560068)
			(end 0.750062 1.560068)
			(stroke
				(width 0.1)
				(type default)
			)
			(layer "F.Fab")
		)
		(fp_line
			(start 0.750062 1.560068)
			(end -0.750062 1.560068)
			(stroke
				(width 0.1)
				(type default)
			)
			(layer "F.Fab")
		)
		(pad "D" smd rect
			(at 1.100074 0 270)
			(size 1.016 1.4224)
			(layers "F.Cu" "F.Mask" "F.Paste")
			(net "FM_PLD_CPU1_PRSNT_HDT_N")
		)
		(pad "G" smd rect
			(at -1.100074 -0.94996 270)
			(size 1.016 1.4224)
			(layers "F.Cu" "F.Mask" "F.Paste")
			(net "CPU1_HDT_BYPASS_SEL")
		)
		(pad "S" smd rect
			(at -1.100074 0.94996 270)
			(size 1.016 1.4224)
			(layers "F.Cu" "F.Mask" "F.Paste")
			(net "GND")
		)
	)
)
